# T6G (Grand Teton) — schematic netlist excerpt (pin names and nets, part order shuffled) for the footprints in the layout excerpt that follows; sources: Cadence DE-HDL packaged netlist, KiCad conversion of 04192023_DAF0TMB3IC0_F0TG_MB_C_brd_V02_OCP.brd

L10  Q_INDUCTOR  100NH/16A IND  pkg SMLF  page 356 : \1\ = P0V9_CPU1_RT_2D ; \2\ = P0V9_CPU1_RT3_2A
C6648  Q_CAP_DIFFBUS  DIFF BUS_0.22UF 6.3V 20% X6S  pkg C0201  page 319 : \1\ = P5E_CPU1_P0_TX_BUF_C_DN<9> ; \2\ = P5E_CPU1_P0_TX_BUF_DN<9>
R613  Q_RES  0 5% CHIP  pkg 0201LF  page 298 : A = CLK_100M_RETIMER_CPU0_P2_R_DP ; B = CLK_100M_RETIMER_CPU0_P2_DP
PR329  Q_RES  4.87K 1% EMPTY  pkg 0402LF  page 225 : A = GND ; B = PVDD11_S3_P1_LSET2

(kicad_pcb
	(version 20260206)
	(generator "pcbnew")
	(generator_version "10.0")
	(general
		(thickness 1.6)
		(legacy_teardrops no)
	)
	(paper "A4")
	(title_block
		(title "04192023_DAF0TMB3IC0_F0TG_MB_C_brd_V02_OCP.brd")
		(comment 1 "Grand Teton / footprints 1557-1560 of 8354")
	)
	(layers
		(0 "F.Cu" signal "TOP")
		(4 "In1.Cu" signal "GND")
		(6 "In2.Cu" signal "IN1")
		(8 "In3.Cu" signal "GND1")
		(10 "In4.Cu" signal "IN2")
		(12 "In5.Cu" signal "GND2")
		(14 "In6.Cu" signal "IN3")
		(16 "In7.Cu" signal "GND3")
		(18 "In8.Cu" signal "VCC")
		(20 "In9.Cu" signal "VCC1")
		(22 "In10.Cu" signal "GND4")
		(24 "In11.Cu" signal "IN4")
		(26 "In12.Cu" signal "GND5")
		(28 "In13.Cu" signal "IN5")
		(30 "In14.Cu" signal "GND6")
		(32 "In15.Cu" signal "IN6")
		(34 "In16.Cu" signal "GND7")
		(2 "B.Cu" signal "BOTTOM")
		(9 "F.Adhes" user "F.Adhesive")
		(11 "B.Adhes" user "B.Adhesive")
		(13 "F.Paste" user "Package Geometry/Pastemask Top")
		(15 "B.Paste" user "Package Geometry/Pastemask Bottom")
		(5 "F.SilkS" user "Ref Des/Silkscreen Top")
		(7 "B.SilkS" user "Ref Des/Silkscreen Bottom")
		(1 "F.Mask" user "Board Geometry/Soldermask Top")
		(3 "B.Mask" user "Board Geometry/Soldermask Bottom")
		(17 "Dwgs.User" user "User.Drawings")
		(19 "Cmts.User" user "User.Comments")
		(21 "Eco1.User" user "User.Eco1")
		(23 "Eco2.User" user "User.Eco2")
		(25 "Edge.Cuts" user "Board Geometry/Outline")
		(27 "Margin" user)
		(31 "F.CrtYd" user "Package Geometry/Place Bound Top")
		(29 "B.CrtYd" user "Package Geometry/Place Bound Bottom")
		(35 "F.Fab" user "Ref Des/Assembly Top")
		(33 "B.Fab" user "Ref Des/Assembly Bottom")
	)
	(footprint ""
		(layer "F.Cu")
		(at 107.722924 -392.521694)
		(property "Reference" "L10"
			(at -4.85648 -0.739648 0)
			(unlocked yes)
			(layer "F.SilkS")
			(effects
				(font
					(size 0.7874 0.5842)
					(thickness 0.1524)
				)
				(justify left)
			)
		)
		(property "Value" ""
			(at 0 0 0)
			(layer "F.Fab")
			(effects
				(font
					(size 1.27 1.27)
				)
			)
		)
		(duplicate_pad_numbers_are_jumpers no)
		(fp_line
			(start -2.249932 -2.249932)
			(end 2.249932 -2.249932)
			(stroke
				(width 0.1524)
				(type default)
			)
			(layer "F.SilkS")
		)
		(fp_line
			(start -2.249932 -1.3843)
			(end -2.249932 -2.249932)
			(stroke
				(width 0.1524)
				(type default)
			)
			(layer "F.SilkS")
		)
		(fp_line
			(start -2.249932 2.249932)
			(end -2.249932 1.3843)
			(stroke
				(width 0.1524)
				(type default)
			)
			(layer "F.SilkS")
		)
		(fp_line
			(start 2.249932 -2.249932)
			(end 2.249932 -1.3843)
			(stroke
				(width 0.1524)
				(type default)
			)
			(layer "F.SilkS")
		)
		(fp_line
			(start 2.249932 1.3843)
			(end 2.249932 2.249932)
			(stroke
				(width 0.1524)
				(type default)
			)
			(layer "F.SilkS")
		)
		(fp_line
			(start 2.249932 2.249932)
			(end -2.249932 2.249932)
			(stroke
				(width 0.1524)
				(type default)
			)
			(layer "F.SilkS")
		)
		(fp_line
			(start -2.249932 -2.249932)
			(end 2.249932 -2.249932)
			(stroke
				(width 0.1)
				(type default)
			)
			(layer "F.Fab")
		)
		(fp_line
			(start -2.249932 2.249932)
			(end -2.249932 -2.249932)
			(stroke
				(width 0.1)
				(type default)
			)
			(layer "F.Fab")
		)
		(fp_line
			(start 2.249932 -2.249932)
			(end 2.249932 2.249932)
			(stroke
				(width 0.1)
				(type default)
			)
			(layer "F.Fab")
		)
		(fp_line
			(start 2.249932 2.249932)
			(end -2.249932 2.249932)
			(stroke
				(width 0.1)
				(type default)
			)
			(layer "F.Fab")
		)
		(pad "1" smd rect
			(at -1.82499 0)
			(size 1.0668 2.5146)
			(layers "F.Cu" "F.Mask" "F.Paste")
			(net "P0V9_CPU1_RT_2D")
		)
		(pad "2" smd rect
			(at 1.82499 0)
			(size 1.0668 2.5146)
			(layers "F.Cu" "F.Mask" "F.Paste")
			(net "P0V9_CPU1_RT3_2A")
		)
	)
	(footprint ""
		(layer "F.Cu")
		(at 398.155668 -396.146274)
		(property "Reference" "R613"
			(at 0 0 0)
			(layer "F.SilkS")
			(hide yes)
			(effects
				(font
					(size 1.27 1.27)
				)
			)
		)
		(property "Value" ""
			(at 0 0 0)
			(layer "F.Fab")
			(effects
				(font
					(size 1.27 1.27)
				)
			)
		)
		(duplicate_pad_numbers_are_jumpers no)
		(fp_line
			(start -0.32512 -0.175006)
			(end 0.32512 -0.175006)
			(stroke
				(width 0.1)
				(type default)
			)
			(layer "F.Fab")
		)
		(fp_line
			(start -0.32512 0.175006)
			(end -0.32512 -0.175006)
			(stroke
				(width 0.1)
				(type default)
			)
			(layer "F.Fab")
		)
		(fp_line
			(start 0.32512 -0.175006)
			(end 0.32512 0.175006)
			(stroke
				(width 0.1)
				(type default)
			)
			(layer "F.Fab")
		)
		(fp_line
			(start 0.32512 0.175006)
			(end -0.32512 0.175006)
			(stroke
				(width 0.1)
				(type default)
			)
			(layer "F.Fab")
		)
		(pad "1" smd rect
			(at -0.2667 0)
			(size 0.3048 0.381)
			(layers "F.Cu" "F.Mask" "F.Paste")
			(net "CLK_100M_RETIMER_CPU0_P2_R_DP")
		)
		(pad "2" smd rect
			(at 0.2667 0 180)
			(size 0.3048 0.381)
			(layers "F.Cu" "F.Mask" "F.Paste")
			(net "CLK_100M_RETIMER_CPU0_P2_DP")
		)
	)
	(footprint ""
		(layer "F.Cu")
		(at 75.337924 -408.517344 -90)
		(property "Reference" "C6648"
			(at 0 0 270)
			(layer "F.SilkS")
			(hide yes)
			(effects
				(font
					(size 1.27 1.27)
				)
			)
		)
		(property "Value" ""
			(at 0 0 270)
			(layer "F.Fab")
			(effects
				(font
					(size 1.27 1.27)
				)
			)
		)
		(duplicate_pad_numbers_are_jumpers no)
		(fp_line
			(start -0.299974 0.150114)
			(end -0.299974 -0.150114)
			(stroke
				(width 0.1)
				(type default)
			)
			(layer "F.Fab")
		)
		(fp_line
			(start 0.299974 0.150114)
			(end -0.299974 0.150114)
			(stroke
				(width 0.1)
				(type default)
			)
			(layer "F.Fab")
		)
		(fp_line
			(start -0.299974 -0.150114)
			(end 0.299974 -0.150114)
			(stroke
				(width 0.1)
				(type default)
			)
			(layer "F.Fab")
		)
		(fp_line
			(start 0.299974 -0.150114)
			(end 0.299974 0.150114)
			(stroke
				(width 0.1)
				(type default)
			)
			(layer "F.Fab")
		)
		(pad "1" smd rect
			(at -0.2667 0 270)
			(size 0.3048 0.381)
			(layers "F.Cu" "F.Mask" "F.Paste")
			(net "P5E_CPU1_P0_TX_BUF_C_DN<9>")
		)
		(pad "2" smd rect
			(at 0.2667 0 270)
			(size 0.3048 0.381)
			(layers "F.Cu" "F.Mask" "F.Paste")
			(net "P5E_CPU1_P0_TX_BUF_DN<9>")
		)
	)
	(footprint ""
		(layer "F.Cu")
		(at 189.941962 -356.532434 180)
		(property "Reference" "PR329"
			(at 0 0 180)
			(layer "F.SilkS")
			(hide yes)
			(effects
				(font
					(size 1.27 1.27)
				)
			)
		)
		(property "Value" ""
			(at 0 0 180)
			(layer "F.Fab")
			(effects
				(font
					(size 1.27 1.27)
				)
			)
		)
		(duplicate_pad_numbers_are_jumpers no)
		(fp_line
			(start 0.7874 0.4064)
			(end -0.7874 0.4064)
			(stroke
				(width 0.1524)
				(type default)
			)
			(layer "F.SilkS")
		)
		(fp_line
			(start 0.7874 -0.4064)
			(end 0.7874 0.4064)
			(stroke
				(width 0.1524)
				(type default)
			)
			(layer "F.SilkS")
		)
		(fp_line
			(start -0.7874 0.4064)
			(end -0.7874 -0.4064)
			(stroke
				(width 0.1524)
				(type default)
			)
			(layer "F.SilkS")
		)
		(fp_line
			(start -0.7874 -0.4064)
			(end 0.7874 -0.4064)
			(stroke
				(width 0.1524)
				(type default)
			)
			(layer "F.SilkS")
		)
		(fp_line
			(start 0.67945 0.3048)
			(end 0.120396 0.3048)
			(stroke
				(width 0.1)
				(type default)
			)
			(layer "F.Fab")
		)
		(fp_line
			(start 0.67945 -0.3048)
			(end 0.67945 0.3048)
			(stroke
				(width 0.1)
				(type default)
			)
			(layer "F.Fab")
		)
		(fp_line
			(start 0.12065 -0.2794)
			(end 0.12065 -0.3048)
			(stroke
				(width 0.1)
				(type default)
			)
			(layer "F.Fab")
		)
		(fp_line
			(start 0.12065 -0.3048)
			(end 0.67945 -0.3048)
			(stroke
				(width 0.1)
				(type default)
			)
			(layer "F.Fab")
		)
		(fp_line
			(start 0.120396 0.3048)
			(end 0.120396 0.2794)
			(stroke
				(width 0.1)
				(type default)
			)
			(layer "F.Fab")
		)
		(fp_line
			(start 0.120396 0.2794)
			(end -0.12065 0.2794)
			(stroke
				(width 0.1)
				(type default)
			)
			(layer "F.Fab")
		)
		(fp_line
			(start -0.12065 0.3048)
			(end -0.67945 0.3048)
			(stroke
				(width 0.1)
				(type default)
			)
			(layer "F.Fab")
		)
		(fp_line
			(start -0.12065 0.2794)
			(end -0.12065 0.3048)
			(stroke
				(width 0.1)
				(type default)
			)
			(layer "F.Fab")
		)
		(fp_line
			(start -0.12065 -0.2794)
			(end 0.12065 -0.2794)
			(stroke
				(width 0.1)
				(type default)
			)
			(layer "F.Fab")
		)
		(fp_line
			(start -0.12065 -0.305054)
			(end -0.12065 -0.2794)
			(stroke
				(width 0.1)
				(type default)
			)
			(layer "F.Fab")
		)
		(fp_line
			(start -0.67945 0.3048)
			(end -0.67945 -0.305054)
			(stroke
				(width 0.1)
				(type default)
			)
			(layer "F.Fab")
		)
		(fp_line
			(start -0.67945 -0.305054)
			(end -0.12065 -0.305054)
			(stroke
				(width 0.1)
				(type default)
			)
			(layer "F.Fab")
		)
		(pad "1" smd circle
			(at -0.40005 0 180)
			(size 0 0)
			(layers "F.Cu" "F.Mask" "F.Paste")
			(net "GND")
		)
		(pad "2" smd circle
			(at 0.40005 0 180)
			(size 0 0)
			(layers "F.Cu" "F.Mask" "F.Paste")
			(net "PVDD11_S3_P1_LSET2")
		)
	)
)
